# S9S_MB_2U (Grand Teton) — schematic netlist excerpt (pin names and nets, part order shuffled) for the footprints in the layout excerpt that follows; sources: Cadence DE-HDL packaged netlist, KiCad conversion of 03242023_DA0F0TMBIJ0_F0T_Motherboard_J_brd_V01_OCP.brd

R3684  Q_RES  0 5% CHIP  pkg 0402LF  page 250 : A = P3V3_ADC ; B = P3V3_ADC_TIC

U307  MOSFET_N  BSS138K IC  pkg SMLF  page 257
  DRAIN  = FM_LPC_ESPI_SEL
  GATE  = FM_ESPI_PLD_R_EN_BUF_R
  SOURCE  = GND

U89  MOSFET_N  BSS138K IC  pkg SMLF  page 218
  DRAIN  = FM_PLD_HEARTBEAT_LVC3_D
  GATE  = FM_PLD_HEARTBEAT_LVC3
  SOURCE  = GND

(kicad_pcb
	(version 20260206)
	(generator "pcbnew")
	(generator_version "10.0")
	(general
		(thickness 1.6)
		(legacy_teardrops no)
	)
	(paper "A4")
	(title_block
		(title "03242023_DA0F0TMBIJ0_F0T_Motherboard_J_brd_V01_OCP.brd")
		(comment 1 "Grand Teton / footprints 916-918 of 6105")
	)
	(layers
		(0 "F.Cu" signal "TOP")
		(4 "In1.Cu" signal "GND")
		(6 "In2.Cu" signal "IN1")
		(8 "In3.Cu" signal "GND1")
		(10 "In4.Cu" signal "IN2")
		(12 "In5.Cu" signal "GND2")
		(14 "In6.Cu" signal "IN3")
		(16 "In7.Cu" signal "GND3")
		(18 "In8.Cu" signal "VCC")
		(20 "In9.Cu" signal "VCC1")
		(22 "In10.Cu" signal "GND4")
		(24 "In11.Cu" signal "IN4")
		(26 "In12.Cu" signal "GND5")
		(28 "In13.Cu" signal "IN5")
		(30 "In14.Cu" signal "GND6")
		(32 "In15.Cu" signal "IN6")
		(34 "In16.Cu" signal "GND7")
		(2 "B.Cu" signal "BOTTOM")
		(9 "F.Adhes" user "F.Adhesive")
		(11 "B.Adhes" user "B.Adhesive")
		(13 "F.Paste" user "Package Geometry/Pastemask Top")
		(15 "B.Paste" user "Package Geometry/Pastemask Bottom")
		(5 "F.SilkS" user "Ref Des/Silkscreen Top")
		(7 "B.SilkS" user "Ref Des/Silkscreen Bottom")
		(1 "F.Mask" user "Board Geometry/Soldermask Top")
		(3 "B.Mask" user "Board Geometry/Soldermask Bottom")
		(17 "Dwgs.User" user "User.Drawings")
		(19 "Cmts.User" user "User.Comments")
		(21 "Eco1.User" user "User.Eco1")
		(23 "Eco2.User" user "User.Eco2")
		(25 "Edge.Cuts" user "Board Geometry/Outline")
		(27 "Margin" user)
		(31 "F.CrtYd" user "Package Geometry/Place Bound Top")
		(29 "B.CrtYd" user "Package Geometry/Place Bound Bottom")
		(35 "F.Fab" user "Ref Des/Assembly Top")
		(33 "B.Fab" user "Ref Des/Assembly Bottom")
	)
	(footprint ""
		(layer "F.Cu")
		(at 39.827454 -108.047282 180)
		(property "Reference" "R3684"
			(at 0 0 180)
			(layer "F.SilkS")
			(hide yes)
			(effects
				(font
					(size 1.27 1.27)
				)
			)
		)
		(property "Value" ""
			(at 0 0 180)
			(layer "F.Fab")
			(effects
				(font
					(size 1.27 1.27)
				)
			)
		)
		(duplicate_pad_numbers_are_jumpers no)
		(fp_line
			(start 0.7874 0.4064)
			(end -0.7874 0.4064)
			(stroke
				(width 0.1524)
				(type default)
			)
			(layer "F.SilkS")
		)
		(fp_line
			(start 0.7874 -0.4064)
			(end 0.7874 0.4064)
			(stroke
				(width 0.1524)
				(type default)
			)
			(layer "F.SilkS")
		)
		(fp_line
			(start -0.7874 0.4064)
			(end -0.7874 -0.4064)
			(stroke
				(width 0.1524)
				(type default)
			)
			(layer "F.SilkS")
		)
		(fp_line
			(start -0.7874 -0.4064)
			(end 0.7874 -0.4064)
			(stroke
				(width 0.1524)
				(type default)
			)
			(layer "F.SilkS")
		)
		(fp_line
			(start 0.67945 0.3048)
			(end 0.120396 0.3048)
			(stroke
				(width 0.1)
				(type default)
			)
			(layer "F.Fab")
		)
		(fp_line
			(start 0.67945 -0.3048)
			(end 0.67945 0.3048)
			(stroke
				(width 0.1)
				(type default)
			)
			(layer "F.Fab")
		)
		(fp_line
			(start 0.12065 -0.2794)
			(end 0.12065 -0.3048)
			(stroke
				(width 0.1)
				(type default)
			)
			(layer "F.Fab")
		)
		(fp_line
			(start 0.12065 -0.3048)
			(end 0.67945 -0.3048)
			(stroke
				(width 0.1)
				(type default)
			)
			(layer "F.Fab")
		)
		(fp_line
			(start 0.120396 0.3048)
			(end 0.120396 0.2794)
			(stroke
				(width 0.1)
				(type default)
			)
			(layer "F.Fab")
		)
		(fp_line
			(start 0.120396 0.2794)
			(end -0.12065 0.2794)
			(stroke
				(width 0.1)
				(type default)
			)
			(layer "F.Fab")
		)
		(fp_line
			(start -0.12065 0.3048)
			(end -0.67945 0.3048)
			(stroke
				(width 0.1)
				(type default)
			)
			(layer "F.Fab")
		)
		(fp_line
			(start -0.12065 0.2794)
			(end -0.12065 0.3048)
			(stroke
				(width 0.1)
				(type default)
			)
			(layer "F.Fab")
		)
		(fp_line
			(start -0.12065 -0.2794)
			(end 0.12065 -0.2794)
			(stroke
				(width 0.1)
				(type default)
			)
			(layer "F.Fab")
		)
		(fp_line
			(start -0.12065 -0.305054)
			(end -0.12065 -0.2794)
			(stroke
				(width 0.1)
				(type default)
			)
			(layer "F.Fab")
		)
		(fp_line
			(start -0.67945 0.3048)
			(end -0.67945 -0.305054)
			(stroke
				(width 0.1)
				(type default)
			)
			(layer "F.Fab")
		)
		(fp_line
			(start -0.67945 -0.305054)
			(end -0.12065 -0.305054)
			(stroke
				(width 0.1)
				(type default)
			)
			(layer "F.Fab")
		)
		(pad "1" smd rect
			(at -0.40005 0)
			(size 0.4572 0.508)
			(layers "F.Cu" "F.Mask" "F.Paste")
			(net "P3V3_ADC")
		)
		(pad "2" smd rect
			(at 0.40005 0)
			(size 0.4572 0.508)
			(layers "F.Cu" "F.Mask" "F.Paste")
			(net "P3V3_ADC_TIC")
		)
	)
	(footprint ""
		(layer "F.Cu")
		(at 166.77894 -28.044648)
		(property "Reference" "U307"
			(at 1.03632 2.521712 0)
			(unlocked yes)
			(layer "F.SilkS")
			(effects
				(font
					(size 0.7874 0.5842)
					(thickness 0.1524)
				)
			)
		)
		(property "Value" ""
			(at 0 0 0)
			(layer "F.Fab")
			(effects
				(font
					(size 1.27 1.27)
				)
			)
		)
		(duplicate_pad_numbers_are_jumpers no)
		(fp_line
			(start -1.949958 -1.610106)
			(end 1.949958 -1.610106)
			(stroke
				(width 0.1524)
				(type default)
			)
			(layer "F.SilkS")
		)
		(fp_line
			(start -1.949958 1.610106)
			(end -1.949958 -1.610106)
			(stroke
				(width 0.1524)
				(type default)
			)
			(layer "F.SilkS")
		)
		(fp_line
			(start 1.949958 -1.560068)
			(end 1.949958 1.610106)
			(stroke
				(width 0.1524)
				(type default)
			)
			(layer "F.SilkS")
		)
		(fp_line
			(start 1.949958 1.610106)
			(end -1.949958 1.610106)
			(stroke
				(width 0.1524)
				(type default)
			)
			(layer "F.SilkS")
		)
		(fp_line
			(start -0.750062 -1.560068)
			(end 0.750062 -1.560068)
			(stroke
				(width 0.1)
				(type default)
			)
			(layer "F.Fab")
		)
		(fp_line
			(start -0.750062 1.560068)
			(end -0.750062 -1.560068)
			(stroke
				(width 0.1)
				(type default)
			)
			(layer "F.Fab")
		)
		(fp_line
			(start 0.750062 -1.560068)
			(end 0.750062 1.560068)
			(stroke
				(width 0.1)
				(type default)
			)
			(layer "F.Fab")
		)
		(fp_line
			(start 0.750062 1.560068)
			(end -0.750062 1.560068)
			(stroke
				(width 0.1)
				(type default)
			)
			(layer "F.Fab")
		)
		(pad "D" smd rect
			(at 1.100074 0 270)
			(size 1.016 1.4224)
			(layers "F.Cu" "F.Mask" "F.Paste")
			(net "FM_LPC_ESPI_SEL")
		)
		(pad "G" smd rect
			(at -1.100074 -0.94996 270)
			(size 1.016 1.4224)
			(layers "F.Cu" "F.Mask" "F.Paste")
			(net "FM_ESPI_PLD_R_EN_BUF_R")
		)
		(pad "S" smd rect
			(at -1.100074 0.94996 270)
			(size 1.016 1.4224)
			(layers "F.Cu" "F.Mask" "F.Paste")
			(net "GND")
		)
	)
	(footprint ""
		(layer "F.Cu")
		(at 217.12428 -108.321348 90)
		(property "Reference" "U89"
			(at -0.264922 3.129788 0)
			(unlocked yes)
			(layer "F.SilkS")
			(effects
				(font
					(size 0.7874 0.5842)
					(thickness 0.1524)
				)
			)
		)
		(property "Value" ""
			(at 0 0 90)
			(layer "F.Fab")
			(effects
				(font
					(size 1.27 1.27)
				)
			)
		)
		(duplicate_pad_numbers_are_jumpers no)
		(fp_line
			(start -1.949958 -1.610106)
			(end 1.949958 -1.610106)
			(stroke
				(width 0.1524)
				(type default)
			)
			(layer "F.SilkS")
		)
		(fp_line
			(start 1.949958 -1.560068)
			(end 1.949958 1.610106)
			(stroke
				(width 0.1524)
				(type default)
			)
			(layer "F.SilkS")
		)
		(fp_line
			(start 1.949958 1.610106)
			(end -1.949958 1.610106)
			(stroke
				(width 0.1524)
				(type default)
			)
			(layer "F.SilkS")
		)
		(fp_line
			(start -1.949958 1.610106)
			(end -1.949958 -1.610106)
			(stroke
				(width 0.1524)
				(type default)
			)
			(layer "F.SilkS")
		)
		(fp_line
			(start 0.750062 -1.560068)
			(end 0.750062 1.560068)
			(stroke
				(width 0.1)
				(type default)
			)
			(layer "F.Fab")
		)
		(fp_line
			(start -0.750062 -1.560068)
			(end 0.750062 -1.560068)
			(stroke
				(width 0.1)
				(type default)
			)
			(layer "F.Fab")
		)
		(fp_line
			(start 0.750062 1.560068)
			(end -0.750062 1.560068)
			(stroke
				(width 0.1)
				(type default)
			)
			(layer "F.Fab")
		)
		(fp_line
			(start -0.750062 1.560068)
			(end -0.750062 -1.560068)
			(stroke
				(width 0.1)
				(type default)
			)
			(layer "F.Fab")
		)
		(pad "D" smd rect
			(at 1.100074 0)
			(size 1.016 1.4224)
			(layers "F.Cu" "F.Mask" "F.Paste")
			(net "FM_PLD_HEARTBEAT_LVC3_D")
		)
		(pad "G" smd rect
			(at -1.100074 -0.94996)
			(size 1.016 1.4224)
			(layers "F.Cu" "F.Mask" "F.Paste")
			(net "FM_PLD_HEARTBEAT_LVC3")
		)
		(pad "S" smd rect
			(at -1.100074 0.94996)
			(size 1.016 1.4224)
			(layers "F.Cu" "F.Mask" "F.Paste")
			(net "GND")
		)
	)
)
